# T6G (Grand Teton) — schematic netlist excerpt (pin names and nets, part order shuffled) for the footprints in the layout excerpt that follows; sources: Cadence DE-HDL packaged netlist, KiCad conversion of 04192023_DAF0TMB3IC0_F0TG_MB_C_brd_V02_OCP.brd

R331  Q_RES  2.2K 5% EMPTY  pkg 0402LF  page 151 : A = SMB_FAN_3V3AUX_SDA ; B = P3V3_AUX
R112  Q_RES  1K 1% EMPTY  pkg 0402LF  page 106 : A = P3V3 ; B = PWRGD_CHI_CPU1_DIMM

(kicad_pcb
	(version 20260206)
	(generator "pcbnew")
	(generator_version "10.0")
	(general
		(thickness 1.6)
		(legacy_teardrops no)
	)
	(paper "A4")
	(title_block
		(title "04192023_DAF0TMB3IC0_F0TG_MB_C_brd_V02_OCP.brd")
		(comment 1 "Grand Teton / footprints 5099-5100 of 8354")
	)
	(layers
		(0 "F.Cu" signal "TOP")
		(4 "In1.Cu" signal "GND")
		(6 "In2.Cu" signal "IN1")
		(8 "In3.Cu" signal "GND1")
		(10 "In4.Cu" signal "IN2")
		(12 "In5.Cu" signal "GND2")
		(14 "In6.Cu" signal "IN3")
		(16 "In7.Cu" signal "GND3")
		(18 "In8.Cu" signal "VCC")
		(20 "In9.Cu" signal "VCC1")
		(22 "In10.Cu" signal "GND4")
		(24 "In11.Cu" signal "IN4")
		(26 "In12.Cu" signal "GND5")
		(28 "In13.Cu" signal "IN5")
		(30 "In14.Cu" signal "GND6")
		(32 "In15.Cu" signal "IN6")
		(34 "In16.Cu" signal "GND7")
		(2 "B.Cu" signal "BOTTOM")
		(9 "F.Adhes" user "F.Adhesive")
		(11 "B.Adhes" user "B.Adhesive")
		(13 "F.Paste" user "Package Geometry/Pastemask Top")
		(15 "B.Paste" user "Package Geometry/Pastemask Bottom")
		(5 "F.SilkS" user "Ref Des/Silkscreen Top")
		(7 "B.SilkS" user "Ref Des/Silkscreen Bottom")
		(1 "F.Mask" user "Board Geometry/Soldermask Top")
		(3 "B.Mask" user "Board Geometry/Soldermask Bottom")
		(17 "Dwgs.User" user "User.Drawings")
		(19 "Cmts.User" user "User.Comments")
		(21 "Eco1.User" user "User.Eco1")
		(23 "Eco2.User" user "User.Eco2")
		(25 "Edge.Cuts" user "Board Geometry/Outline")
		(27 "Margin" user)
		(31 "F.CrtYd" user "Package Geometry/Place Bound Top")
		(29 "B.CrtYd" user "Package Geometry/Place Bound Bottom")
		(35 "F.Fab" user "Ref Des/Assembly Top")
		(33 "B.Fab" user "Ref Des/Assembly Bottom")
	)
	(footprint ""
		(layer "B.Cu")
		(at 158.440628 -16.553942 180)
		(property "Reference" "R331"
			(at 0 0 0)
			(layer "B.SilkS")
			(hide yes)
			(effects
				(font
					(size 1.27 1.27)
				)
				(justify mirror)
			)
		)
		(property "Value" ""
			(at 0 0 0)
			(layer "B.Fab")
			(effects
				(font
					(size 1.27 1.27)
				)
				(justify mirror)
			)
		)
		(duplicate_pad_numbers_are_jumpers no)
		(fp_line
			(start 0.7874 0.4064)
			(end 0.7874 -0.4064)
			(stroke
				(width 0.1524)
				(type default)
			)
			(layer "B.SilkS")
		)
		(fp_line
			(start 0.7874 -0.4064)
			(end -0.7874 -0.4064)
			(stroke
				(width 0.1524)
				(type default)
			)
			(layer "B.SilkS")
		)
		(fp_line
			(start -0.7874 0.4064)
			(end 0.7874 0.4064)
			(stroke
				(width 0.1524)
				(type default)
			)
			(layer "B.SilkS")
		)
		(fp_line
			(start -0.7874 -0.4064)
			(end -0.7874 0.4064)
			(stroke
				(width 0.1524)
				(type default)
			)
			(layer "B.SilkS")
		)
		(fp_line
			(start 0.67945 0.3048)
			(end 0.67945 -0.305054)
			(stroke
				(width 0.1)
				(type default)
			)
			(layer "B.Fab")
		)
		(fp_line
			(start 0.67945 -0.305054)
			(end 0.12065 -0.305054)
			(stroke
				(width 0.1)
				(type default)
			)
			(layer "B.Fab")
		)
		(fp_line
			(start 0.12065 0.3048)
			(end 0.67945 0.3048)
			(stroke
				(width 0.1)
				(type default)
			)
			(layer "B.Fab")
		)
		(fp_line
			(start 0.12065 0.2794)
			(end 0.12065 0.3048)
			(stroke
				(width 0.1)
				(type default)
			)
			(layer "B.Fab")
		)
		(fp_line
			(start 0.12065 -0.2794)
			(end -0.12065 -0.2794)
			(stroke
				(width 0.1)
				(type default)
			)
			(layer "B.Fab")
		)
		(fp_line
			(start 0.12065 -0.305054)
			(end 0.12065 -0.2794)
			(stroke
				(width 0.1)
				(type default)
			)
			(layer "B.Fab")
		)
		(fp_line
			(start -0.120396 0.3048)
			(end -0.120396 0.2794)
			(stroke
				(width 0.1)
				(type default)
			)
			(layer "B.Fab")
		)
		(fp_line
			(start -0.120396 0.2794)
			(end 0.12065 0.2794)
			(stroke
				(width 0.1)
				(type default)
			)
			(layer "B.Fab")
		)
		(fp_line
			(start -0.12065 -0.2794)
			(end -0.12065 -0.3048)
			(stroke
				(width 0.1)
				(type default)
			)
			(layer "B.Fab")
		)
		(fp_line
			(start -0.12065 -0.3048)
			(end -0.67945 -0.3048)
			(stroke
				(width 0.1)
				(type default)
			)
			(layer "B.Fab")
		)
		(fp_line
			(start -0.67945 0.3048)
			(end -0.120396 0.3048)
			(stroke
				(width 0.1)
				(type default)
			)
			(layer "B.Fab")
		)
		(fp_line
			(start -0.67945 -0.3048)
			(end -0.67945 0.3048)
			(stroke
				(width 0.1)
				(type default)
			)
			(layer "B.Fab")
		)
		(pad "1" smd circle
			(at 0.40005 0)
			(size 0 0)
			(layers "B.Cu" "B.Mask" "B.Paste")
			(net "SMB_FAN_3V3AUX_SDA")
		)
		(pad "2" smd circle
			(at -0.40005 0)
			(size 0 0)
			(layers "B.Cu" "B.Mask" "B.Paste")
			(net "P3V3_AUX")
		)
	)
	(footprint ""
		(layer "B.Cu")
		(at 180.271928 -193.996564)
		(property "Reference" "R112"
			(at 0 0 0)
			(layer "B.SilkS")
			(hide yes)
			(effects
				(font
					(size 1.27 1.27)
				)
				(justify mirror)
			)
		)
		(property "Value" ""
			(at 0 0 0)
			(layer "B.Fab")
			(effects
				(font
					(size 1.27 1.27)
				)
				(justify mirror)
			)
		)
		(duplicate_pad_numbers_are_jumpers no)
		(fp_line
			(start -0.7874 -0.4064)
			(end -0.7874 0.4064)
			(stroke
				(width 0.1524)
				(type default)
			)
			(layer "B.SilkS")
		)
		(fp_line
			(start -0.7874 0.4064)
			(end 0.7874 0.4064)
			(stroke
				(width 0.1524)
				(type default)
			)
			(layer "B.SilkS")
		)
		(fp_line
			(start 0.7874 -0.4064)
			(end -0.7874 -0.4064)
			(stroke
				(width 0.1524)
				(type default)
			)
			(layer "B.SilkS")
		)
		(fp_line
			(start 0.7874 0.4064)
			(end 0.7874 -0.4064)
			(stroke
				(width 0.1524)
				(type default)
			)
			(layer "B.SilkS")
		)
		(fp_line
			(start -0.67945 -0.3048)
			(end -0.67945 0.3048)
			(stroke
				(width 0.1)
				(type default)
			)
			(layer "B.Fab")
		)
		(fp_line
			(start -0.67945 0.3048)
			(end -0.120396 0.3048)
			(stroke
				(width 0.1)
				(type default)
			)
			(layer "B.Fab")
		)
		(fp_line
			(start -0.12065 -0.3048)
			(end -0.67945 -0.3048)
			(stroke
				(width 0.1)
				(type default)
			)
			(layer "B.Fab")
		)
		(fp_line
			(start -0.12065 -0.2794)
			(end -0.12065 -0.3048)
			(stroke
				(width 0.1)
				(type default)
			)
			(layer "B.Fab")
		)
		(fp_line
			(start -0.120396 0.2794)
			(end 0.12065 0.2794)
			(stroke
				(width 0.1)
				(type default)
			)
			(layer "B.Fab")
		)
		(fp_line
			(start -0.120396 0.3048)
			(end -0.120396 0.2794)
			(stroke
				(width 0.1)
				(type default)
			)
			(layer "B.Fab")
		)
		(fp_line
			(start 0.12065 -0.305054)
			(end 0.12065 -0.2794)
			(stroke
				(width 0.1)
				(type default)
			)
			(layer "B.Fab")
		)
		(fp_line
			(start 0.12065 -0.2794)
			(end -0.12065 -0.2794)
			(stroke
				(width 0.1)
				(type default)
			)
			(layer "B.Fab")
		)
		(fp_line
			(start 0.12065 0.2794)
			(end 0.12065 0.3048)
			(stroke
				(width 0.1)
				(type default)
			)
			(layer "B.Fab")
		)
		(fp_line
			(start 0.12065 0.3048)
			(end 0.67945 0.3048)
			(stroke
				(width 0.1)
				(type default)
			)
			(layer "B.Fab")
		)
		(fp_line
			(start 0.67945 -0.305054)
			(end 0.12065 -0.305054)
			(stroke
				(width 0.1)
				(type default)
			)
			(layer "B.Fab")
		)
		(fp_line
			(start 0.67945 0.3048)
			(end 0.67945 -0.305054)
			(stroke
				(width 0.1)
				(type default)
			)
			(layer "B.Fab")
		)
		(pad "1" smd circle
			(at 0.40005 0 180)
			(size 0 0)
			(layers "B.Cu" "B.Mask" "B.Paste")
			(net "P3V3")
		)
		(pad "2" smd circle
			(at -0.40005 0 180)
			(size 0 0)
			(layers "B.Cu" "B.Mask" "B.Paste")
			(net "PWRGD_CHI_CPU1_DIMM")
		)
	)
)
